# TIMECARD (Time Appliance Project (Time Card)) — schematic netlist excerpt (pin names and nets, part order shuffled) for the footprints in the layout excerpt that follows; sources: Cadence DE-HDL packaged netlist, KiCad conversion of R4006-B0001-02_R01.brd

SP1  SOLDER_PREFORM  pkg 0201_SOLDER_PREFORM_4MIL  page 32 : \1\ = SG ; \2\ = XP5R0V_AGND
R135  RESISTOR  0OHM -  pkg SMC_0402R_H016  page 10 : \1\ = FT4232_FPGA_TDO ; \2\ = FPGA_TDO
R105  RESISTOR  0OHM -  pkg SMC_0402R_H016  page 21 : \1\ = MUX_USB_DM ; \2\ = MAC_USB_DM

(kicad_pcb
	(version 20260206)
	(generator "pcbnew")
	(generator_version "10.0")
	(general
		(thickness 1.6)
		(legacy_teardrops no)
	)
	(paper "A4")
	(title_block
		(title "timecard-production-celestica-r4006 — R4006-B0001-02_R01.brd")
		(comment 1 "Time Appliance Project (Time Card) / footprints 693-695 of 1113")
	)
	(layers
		(0 "F.Cu" signal "TOP")
		(4 "In1.Cu" signal "L02_GND1")
		(6 "In2.Cu" signal "L03_SIG1")
		(8 "In3.Cu" signal "L04_GND2")
		(10 "In4.Cu" signal "L05_VCC1")
		(12 "In5.Cu" signal "L06_VCC2")
		(14 "In6.Cu" signal "L07_GND3")
		(16 "In7.Cu" signal "L08_SIG2")
		(18 "In8.Cu" signal "L09_GND4")
		(2 "B.Cu" signal "BOTTOM")
		(9 "F.Adhes" user "F.Adhesive")
		(11 "B.Adhes" user "B.Adhesive")
		(13 "F.Paste" user "Package Geometry/Pastemask Top")
		(15 "B.Paste" user "Package Geometry/Pastemask Bottom")
		(5 "F.SilkS" user "Ref Des/Silkscreen Top")
		(7 "B.SilkS" user "Ref Des/Silkscreen Bottom")
		(1 "F.Mask" user "Board Geometry/Soldermask Top")
		(3 "B.Mask" user "Board Geometry/Soldermask Bottom")
		(17 "Dwgs.User" user "User.Drawings")
		(19 "Cmts.User" user "User.Comments")
		(21 "Eco1.User" user "User.Eco1")
		(23 "Eco2.User" user "User.Eco2")
		(25 "Edge.Cuts" user "Board Geometry/Outline")
		(27 "Margin" user)
		(31 "F.CrtYd" user "Package Geometry/Place Bound Top")
		(29 "B.CrtYd" user "Package Geometry/Place Bound Bottom")
		(35 "F.Fab" user "Ref Des/Assembly Top")
		(33 "B.Fab" user "Ref Des/Assembly Bottom")
	)
	(footprint ""
		(layer "B.Cu")
		(at 140.335 -70.358)
		(property "Reference" "R135"
			(at -4.572 -0.34163 0)
			(unlocked yes)
			(layer "B.SilkS")
			(effects
				(font
					(size 0.7874 0.5842)
					(thickness 0.1524)
				)
				(justify mirror)
			)
		)
		(property "Value" "VAL*"
			(at -0.02032 2.13233 0)
			(unlocked yes)
			(layer "B.Fab")
			(hide yes)
			(effects
				(font
					(size 0.7874 0.5842)
					(thickness 0.1524)
				)
				(justify mirror)
			)
		)
		(property "Device Type" "RESISTOR-G155-100R0-J0,0OHM,-"
			(at -0.008382 1.210564 0)
			(unlocked yes)
			(layer "B.Fab")
			(hide yes)
			(effects
				(font
					(size 0.7874 0.5842)
					(thickness 0.1524)
				)
				(justify mirror)
			)
		)
		(property "User Part Number" "PARTNUM*"
			(at -0.02032 4.024884 0)
			(unlocked yes)
			(layer "Cmts.User")
			(hide yes)
			(effects
				(font
					(size 0.7874 0.5842)
					(thickness 0.1524)
				)
				(justify mirror)
			)
		)
		(property "Tolerance" "TOL*"
			(at -0.044704 3.05435 0)
			(unlocked yes)
			(layer "Cmts.User")
			(hide yes)
			(effects
				(font
					(size 0.7874 0.5842)
					(thickness 0.1524)
				)
				(justify mirror)
			)
		)
		(duplicate_pad_numbers_are_jumpers no)
		(fp_line
			(start -1.143 -0.5588)
			(end 1.143 -0.5588)
			(stroke
				(width 0.1)
				(type default)
			)
			(layer "B.SilkS")
		)
		(fp_line
			(start -1.143 0.5588)
			(end -1.143 -0.5588)
			(stroke
				(width 0.1)
				(type default)
			)
			(layer "B.SilkS")
		)
		(fp_line
			(start 1.143 -0.5588)
			(end 1.143 0.5588)
			(stroke
				(width 0.1)
				(type default)
			)
			(layer "B.SilkS")
		)
		(fp_line
			(start 1.143 0.5588)
			(end -1.143 0.5588)
			(stroke
				(width 0.1)
				(type default)
			)
			(layer "B.SilkS")
		)
		(fp_rect
			(start -1.143 -0.5588)
			(end 1.143 0.5588)
			(stroke
				(width 0)
				(type default)
			)
			(fill no)
			(layer "B.CrtYd")
		)
		(fp_line
			(start -0.508 -0.3048)
			(end 0.508 -0.3048)
			(stroke
				(width 0.1)
				(type default)
			)
			(layer "B.Fab")
		)
		(fp_line
			(start -0.508 0.3048)
			(end -0.508 -0.3048)
			(stroke
				(width 0.1)
				(type default)
			)
			(layer "B.Fab")
		)
		(fp_line
			(start 0.508 -0.3048)
			(end 0.508 0.3048)
			(stroke
				(width 0.1)
				(type default)
			)
			(layer "B.Fab")
		)
		(fp_line
			(start 0.508 0.3048)
			(end -0.508 0.3048)
			(stroke
				(width 0.1)
				(type default)
			)
			(layer "B.Fab")
		)
		(pad "1" smd rect
			(at 0.5334 0 180)
			(size 0.7112 0.6096)
			(layers "B.Cu" "B.Mask" "B.Paste")
			(net "FT4232_FPGA_TDO")
		)
		(pad "2" smd rect
			(at -0.5334 0 180)
			(size 0.7112 0.6096)
			(layers "B.Cu" "B.Mask" "B.Paste")
			(net "FPGA_TDO")
		)
		(zone
			(layer "B.Cu")
			(hatch none 0.5)
			(connect_pads
				(clearance 0)
			)
			(min_thickness 0.25)
			(keepout
				(tracks allowed)
				(vias not_allowed)
				(pads allowed)
				(copperpour not_allowed)
				(footprints allowed)
			)
			(placement
				(enabled no)
				(sheetname "")
			)
			(fill
				(thermal_gap 0.5)
				(thermal_bridge_width 0.5)
				(island_removal_mode 0)
			)
			(polygon
				(pts
					(xy 140.2588 -70.6628) (xy 140.2588 -70.0532) (xy 140.4112 -70.0532) (xy 140.4112 -70.6628)
				)
			)
		)
	)
	(footprint ""
		(layer "B.Cu")
		(at 90.2716 -49.059846 180)
		(property "Reference" "R105"
			(at -0.762 2.500884 0)
			(unlocked yes)
			(layer "B.SilkS")
			(effects
				(font
					(size 0.7874 0.5842)
					(thickness 0.1524)
				)
				(justify mirror)
			)
		)
		(property "Value" "VAL*"
			(at -0.02032 2.13233 180)
			(unlocked yes)
			(layer "B.Fab")
			(hide yes)
			(effects
				(font
					(size 0.7874 0.5842)
					(thickness 0.1524)
				)
				(justify mirror)
			)
		)
		(property "Device Type" "RESISTOR-G155-100R0-J0,0OHM,-"
			(at -0.008382 1.210564 180)
			(unlocked yes)
			(layer "B.Fab")
			(hide yes)
			(effects
				(font
					(size 0.7874 0.5842)
					(thickness 0.1524)
				)
				(justify mirror)
			)
		)
		(property "User Part Number" "PARTNUM*"
			(at -0.02032 4.024884 180)
			(unlocked yes)
			(layer "Cmts.User")
			(hide yes)
			(effects
				(font
					(size 0.7874 0.5842)
					(thickness 0.1524)
				)
				(justify mirror)
			)
		)
		(property "Tolerance" "TOL*"
			(at -0.044704 3.05435 180)
			(unlocked yes)
			(layer "Cmts.User")
			(hide yes)
			(effects
				(font
					(size 0.7874 0.5842)
					(thickness 0.1524)
				)
				(justify mirror)
			)
		)
		(duplicate_pad_numbers_are_jumpers no)
		(fp_line
			(start 1.143 0.5588)
			(end -1.143 0.5588)
			(stroke
				(width 0.1)
				(type default)
			)
			(layer "B.SilkS")
		)
		(fp_line
			(start 1.143 -0.5588)
			(end 1.143 0.5588)
			(stroke
				(width 0.1)
				(type default)
			)
			(layer "B.SilkS")
		)
		(fp_line
			(start -1.143 0.5588)
			(end -1.143 -0.5588)
			(stroke
				(width 0.1)
				(type default)
			)
			(layer "B.SilkS")
		)
		(fp_line
			(start -1.143 -0.5588)
			(end 1.143 -0.5588)
			(stroke
				(width 0.1)
				(type default)
			)
			(layer "B.SilkS")
		)
		(fp_rect
			(start 1.143 -0.5588)
			(end -1.143 0.5588)
			(stroke
				(width 0)
				(type default)
			)
			(fill no)
			(layer "B.CrtYd")
		)
		(fp_line
			(start 0.508 0.3048)
			(end -0.508 0.3048)
			(stroke
				(width 0.1)
				(type default)
			)
			(layer "B.Fab")
		)
		(fp_line
			(start 0.508 -0.3048)
			(end 0.508 0.3048)
			(stroke
				(width 0.1)
				(type default)
			)
			(layer "B.Fab")
		)
		(fp_line
			(start -0.508 0.3048)
			(end -0.508 -0.3048)
			(stroke
				(width 0.1)
				(type default)
			)
			(layer "B.Fab")
		)
		(fp_line
			(start -0.508 -0.3048)
			(end 0.508 -0.3048)
			(stroke
				(width 0.1)
				(type default)
			)
			(layer "B.Fab")
		)
		(pad "1" smd rect
			(at 0.5334 0)
			(size 0.7112 0.6096)
			(layers "B.Cu" "B.Mask" "B.Paste")
			(net "MUX_USB_DM")
		)
		(pad "2" smd rect
			(at -0.5334 0)
			(size 0.7112 0.6096)
			(layers "B.Cu" "B.Mask" "B.Paste")
			(net "MAC_USB_DM")
		)
		(zone
			(layer "B.Cu")
			(hatch none 0.5)
			(connect_pads
				(clearance 0)
			)
			(min_thickness 0.25)
			(keepout
				(tracks allowed)
				(vias not_allowed)
				(pads allowed)
				(copperpour not_allowed)
				(footprints allowed)
			)
			(placement
				(enabled no)
				(sheetname "")
			)
			(fill
				(thermal_gap 0.5)
				(thermal_bridge_width 0.5)
				(island_removal_mode 0)
			)
			(polygon
				(pts
					(xy 90.1954 -48.755046) (xy 90.3478 -48.755046) (xy 90.3478 -49.364646) (xy 90.1954 -49.364646)
				)
			)
		)
	)
	(footprint ""
		(layer "B.Cu")
		(at 41.4274 -102.3874)
		(property "Reference" "SP1"
			(at 0.0762 1.18237 0)
			(unlocked yes)
			(layer "B.SilkS")
			(effects
				(font
					(size 0.7874 0.5842)
					(thickness 0.1524)
				)
				(justify mirror)
			)
		)
		(property "Value" ""
			(at 0 0 0)
			(layer "B.Fab")
			(effects
				(font
					(size 1.27 1.27)
				)
				(justify mirror)
			)
		)
		(duplicate_pad_numbers_are_jumpers no)
		(fp_rect
			(start 0.1778 -0.3048)
			(end -0.1778 0.3048)
			(stroke
				(width 0)
				(type default)
			)
			(fill yes)
			(layer "B.Paste")
		)
		(fp_rect
			(start 0.2286 -0.3556)
			(end -0.2286 0.3556)
			(stroke
				(width 0)
				(type default)
			)
			(fill no)
			(layer "B.CrtYd")
		)
		(fp_line
			(start -0.1397 -0.2413)
			(end -0.1397 0.2413)
			(stroke
				(width 0.1)
				(type default)
			)
			(layer "B.Fab")
		)
		(fp_line
			(start -0.1397 0.2413)
			(end 0.1397 0.2413)
			(stroke
				(width 0.1)
				(type default)
			)
			(layer "B.Fab")
		)
		(fp_line
			(start 0.1397 -0.2413)
			(end -0.1397 -0.2413)
			(stroke
				(width 0.1)
				(type default)
			)
			(layer "B.Fab")
		)
		(fp_line
			(start 0.1397 0.2413)
			(end 0.1397 -0.2413)
			(stroke
				(width 0.1)
				(type default)
			)
			(layer "B.Fab")
		)
		(pad "1" smd rect
			(at 0.1143 0 180)
			(size 0.127 0.6096)
			(layers "B.Cu" "B.Mask" "B.Paste")
			(net "SG")
		)
		(pad "2" smd rect
			(at -0.1143 0 180)
			(size 0.127 0.6096)
			(layers "B.Cu" "B.Mask" "B.Paste")
			(net "XP5R0V_AGND")
		)
	)
)
